# S9S_MB_2U (Grand Teton) — schematic netlist excerpt (pin names and nets, part order shuffled) for the footprints in the layout excerpt that follows; sources: Cadence DE-HDL packaged netlist, KiCad conversion of 03242023_DA0F0TMBIJ0_F0T_Motherboard_J_brd_V01_OCP.brd

U16  74LVC1G66GV  IC  pkg SC74AXA  page 133
  Y  = JTAG_CPU0_MUX_GTL_TDO
  Z  = JTAG_MUX_CPU1_GTL_TDI
  GND  = GND
  E  = FM_CPU_EN_R
  VCC  = P3V3_AUX

PJ66  Q_SHORT  EMPTY  pkg SM  page 299 : \1\ = SH_PVPP_HBM_CPU1_P ; \2\ = PVPP_HBM_CPU1
R65  Q_RES  100 1% CHIP  pkg 0402LF  page 44 : A = JTAG_DBP_CPU_GTL_TCK ; B = JTAG_DBP_CPU1_GTL_R_TCK

(kicad_pcb
	(version 20260206)
	(generator "pcbnew")
	(generator_version "10.0")
	(general
		(thickness 1.6)
		(legacy_teardrops no)
	)
	(paper "A4")
	(title_block
		(title "03242023_DA0F0TMBIJ0_F0T_Motherboard_J_brd_V01_OCP.brd")
		(comment 1 "Grand Teton / footprints 6038-6040 of 6105")
	)
	(layers
		(0 "F.Cu" signal "TOP")
		(4 "In1.Cu" signal "GND")
		(6 "In2.Cu" signal "IN1")
		(8 "In3.Cu" signal "GND1")
		(10 "In4.Cu" signal "IN2")
		(12 "In5.Cu" signal "GND2")
		(14 "In6.Cu" signal "IN3")
		(16 "In7.Cu" signal "GND3")
		(18 "In8.Cu" signal "VCC")
		(20 "In9.Cu" signal "VCC1")
		(22 "In10.Cu" signal "GND4")
		(24 "In11.Cu" signal "IN4")
		(26 "In12.Cu" signal "GND5")
		(28 "In13.Cu" signal "IN5")
		(30 "In14.Cu" signal "GND6")
		(32 "In15.Cu" signal "IN6")
		(34 "In16.Cu" signal "GND7")
		(2 "B.Cu" signal "BOTTOM")
		(9 "F.Adhes" user "F.Adhesive")
		(11 "B.Adhes" user "B.Adhesive")
		(13 "F.Paste" user "Package Geometry/Pastemask Top")
		(15 "B.Paste" user "Package Geometry/Pastemask Bottom")
		(5 "F.SilkS" user "Ref Des/Silkscreen Top")
		(7 "B.SilkS" user "Ref Des/Silkscreen Bottom")
		(1 "F.Mask" user "Board Geometry/Soldermask Top")
		(3 "B.Mask" user "Board Geometry/Soldermask Bottom")
		(17 "Dwgs.User" user "User.Drawings")
		(19 "Cmts.User" user "User.Comments")
		(21 "Eco1.User" user "User.Eco1")
		(23 "Eco2.User" user "User.Eco2")
		(25 "Edge.Cuts" user "Board Geometry/Outline")
		(27 "Margin" user)
		(31 "F.CrtYd" user "Package Geometry/Place Bound Top")
		(29 "B.CrtYd" user "Package Geometry/Place Bound Bottom")
		(35 "F.Fab" user "Ref Des/Assembly Top")
		(33 "B.Fab" user "Ref Des/Assembly Bottom")
	)
	(footprint ""
		(layer "B.Cu")
		(at 87.489284 -190.705232 -90)
		(property "Reference" "R65"
			(at 0 0 90)
			(layer "B.SilkS")
			(hide yes)
			(effects
				(font
					(size 1.27 1.27)
				)
				(justify mirror)
			)
		)
		(property "Value" ""
			(at 0 0 90)
			(layer "B.Fab")
			(effects
				(font
					(size 1.27 1.27)
				)
				(justify mirror)
			)
		)
		(duplicate_pad_numbers_are_jumpers no)
		(fp_line
			(start -0.7874 0.4064)
			(end 0.7874 0.4064)
			(stroke
				(width 0.1524)
				(type default)
			)
			(layer "B.SilkS")
		)
		(fp_line
			(start 0.7874 0.4064)
			(end 0.7874 -0.4064)
			(stroke
				(width 0.1524)
				(type default)
			)
			(layer "B.SilkS")
		)
		(fp_line
			(start -0.7874 -0.4064)
			(end -0.7874 0.4064)
			(stroke
				(width 0.1524)
				(type default)
			)
			(layer "B.SilkS")
		)
		(fp_line
			(start 0.7874 -0.4064)
			(end -0.7874 -0.4064)
			(stroke
				(width 0.1524)
				(type default)
			)
			(layer "B.SilkS")
		)
		(fp_line
			(start -0.67945 0.3048)
			(end -0.120396 0.3048)
			(stroke
				(width 0.1)
				(type default)
			)
			(layer "B.Fab")
		)
		(fp_line
			(start -0.120396 0.3048)
			(end -0.120396 0.2794)
			(stroke
				(width 0.1)
				(type default)
			)
			(layer "B.Fab")
		)
		(fp_line
			(start 0.12065 0.3048)
			(end 0.67945 0.3048)
			(stroke
				(width 0.1)
				(type default)
			)
			(layer "B.Fab")
		)
		(fp_line
			(start 0.67945 0.3048)
			(end 0.67945 -0.305054)
			(stroke
				(width 0.1)
				(type default)
			)
			(layer "B.Fab")
		)
		(fp_line
			(start -0.120396 0.2794)
			(end 0.12065 0.2794)
			(stroke
				(width 0.1)
				(type default)
			)
			(layer "B.Fab")
		)
		(fp_line
			(start 0.12065 0.2794)
			(end 0.12065 0.3048)
			(stroke
				(width 0.1)
				(type default)
			)
			(layer "B.Fab")
		)
		(fp_line
			(start -0.12065 -0.2794)
			(end -0.12065 -0.3048)
			(stroke
				(width 0.1)
				(type default)
			)
			(layer "B.Fab")
		)
		(fp_line
			(start 0.12065 -0.2794)
			(end -0.12065 -0.2794)
			(stroke
				(width 0.1)
				(type default)
			)
			(layer "B.Fab")
		)
		(fp_line
			(start -0.67945 -0.3048)
			(end -0.67945 0.3048)
			(stroke
				(width 0.1)
				(type default)
			)
			(layer "B.Fab")
		)
		(fp_line
			(start -0.12065 -0.3048)
			(end -0.67945 -0.3048)
			(stroke
				(width 0.1)
				(type default)
			)
			(layer "B.Fab")
		)
		(fp_line
			(start 0.12065 -0.305054)
			(end 0.12065 -0.2794)
			(stroke
				(width 0.1)
				(type default)
			)
			(layer "B.Fab")
		)
		(fp_line
			(start 0.67945 -0.305054)
			(end 0.12065 -0.305054)
			(stroke
				(width 0.1)
				(type default)
			)
			(layer "B.Fab")
		)
		(pad "1" smd circle
			(at 0.40005 0 90)
			(size 0 0)
			(layers "B.Cu" "B.Mask" "B.Paste")
			(net "JTAG_DBP_CPU_GTL_TCK")
		)
		(pad "2" smd circle
			(at -0.40005 0 90)
			(size 0 0)
			(layers "B.Cu" "B.Mask" "B.Paste")
			(net "JTAG_DBP_CPU1_GTL_R_TCK")
		)
	)
	(footprint ""
		(layer "B.Cu")
		(at 216.986358 -194.41795)
		(property "Reference" "U16"
			(at 2.2606 -2.352548 0)
			(unlocked yes)
			(layer "B.SilkS")
			(effects
				(font
					(size 0.7874 0.5842)
					(thickness 0.1524)
				)
				(justify left mirror)
			)
		)
		(property "Value" ""
			(at 0 0 0)
			(layer "B.Fab")
			(effects
				(font
					(size 1.27 1.27)
				)
				(justify mirror)
			)
		)
		(duplicate_pad_numbers_are_jumpers no)
		(fp_line
			(start -2.032 -1.549908)
			(end -2.032 1.549908)
			(stroke
				(width 0.1524)
				(type default)
			)
			(layer "B.SilkS")
		)
		(fp_line
			(start -2.032 1.549908)
			(end 2.032 1.549908)
			(stroke
				(width 0.1524)
				(type default)
			)
			(layer "B.SilkS")
		)
		(fp_line
			(start 2.032 -1.549908)
			(end -2.032 -1.549908)
			(stroke
				(width 0.1524)
				(type default)
			)
			(layer "B.SilkS")
		)
		(fp_line
			(start 2.032 1.549908)
			(end 2.032 -1.549908)
			(stroke
				(width 0.1524)
				(type default)
			)
			(layer "B.SilkS")
		)
		(fp_poly
			(pts
				(xy 2.9464 -1.2192) (xy 2.9464 -0.7112) (xy 2.1844 -0.9652)
			)
			(stroke
				(width 0)
				(type default)
			)
			(fill yes)
			(layer "B.SilkS")
		)
		(fp_line
			(start -0.849884 -1.549908)
			(end 0.849884 -1.549908)
			(stroke
				(width 0.1)
				(type default)
			)
			(layer "B.Fab")
		)
		(fp_line
			(start -0.849884 1.549908)
			(end -0.849884 -1.549908)
			(stroke
				(width 0.1)
				(type default)
			)
			(layer "B.Fab")
		)
		(fp_line
			(start 0.849884 -1.549908)
			(end 0.849884 1.549908)
			(stroke
				(width 0.1)
				(type default)
			)
			(layer "B.Fab")
		)
		(fp_line
			(start 0.849884 1.549908)
			(end -0.849884 1.549908)
			(stroke
				(width 0.1)
				(type default)
			)
			(layer "B.Fab")
		)
		(fp_poly
			(pts
				(xy 2.9464 -1.2192) (xy 2.9464 -0.7112) (xy 2.1844 -0.9652)
			)
			(stroke
				(width 0)
				(type default)
			)
			(fill yes)
			(layer "B.Fab")
		)
		(pad "1" smd rect
			(at 1.225042 -0.94996 270)
			(size 0.4572 1.3208)
			(layers "B.Cu" "B.Mask" "B.Paste")
			(net "JTAG_CPU0_MUX_GTL_TDO")
		)
		(pad "2" smd rect
			(at 1.225042 0 270)
			(size 0.4572 1.3208)
			(layers "B.Cu" "B.Mask" "B.Paste")
			(net "JTAG_MUX_CPU1_GTL_TDI")
		)
		(pad "3" smd rect
			(at 1.225042 0.94996 270)
			(size 0.4572 1.3208)
			(layers "B.Cu" "B.Mask" "B.Paste")
			(net "GND")
		)
		(pad "4" smd rect
			(at -1.225042 0.94996 270)
			(size 0.4572 1.3208)
			(layers "B.Cu" "B.Mask" "B.Paste")
			(net "FM_CPU_EN_R")
		)
		(pad "5" smd rect
			(at -1.225042 -0.94996 270)
			(size 0.4572 1.3208)
			(layers "B.Cu" "B.Mask" "B.Paste")
			(net "P3V3_AUX")
		)
	)
	(footprint ""
		(layer "B.Cu")
		(at 120.458484 -359.596436 -90)
		(property "Reference" "PJ66"
			(at -4.067302 -0.128016 0)
			(unlocked yes)
			(layer "B.SilkS")
			(effects
				(font
					(size 0.7874 0.5842)
					(thickness 0.1524)
				)
				(justify left mirror)
			)
		)
		(property "Value" ""
			(at 0 0 90)
			(layer "B.Fab")
			(effects
				(font
					(size 1.27 1.27)
				)
				(justify mirror)
			)
		)
		(duplicate_pad_numbers_are_jumpers no)
		(pad "1" smd circle
			(at 0.7493 0)
			(size 0 0)
			(layers "B.Cu" "B.Mask" "B.Paste")
			(net "SH_PVPP_HBM_CPU1_P")
		)
		(pad "2" smd rect
			(at -0.7493 0 180)
			(size 0.7112 0.8128)
			(layers "B.Cu" "B.Mask" "B.Paste")
			(net "PVPP_HBM_CPU1")
		)
		(zone
			(layer "B.Cu")
			(hatch none 0.5)
			(connect_pads
				(clearance 0)
			)
			(min_thickness 0.25)
			(keepout
				(tracks allowed)
				(vias not_allowed)
				(pads allowed)
				(copperpour not_allowed)
				(footprints allowed)
			)
			(placement
				(enabled no)
				(sheetname "")
			)
			(fill
				(thermal_gap 0.5)
				(thermal_bridge_width 0.5)
				(island_removal_mode 0)
			)
			(polygon
				(pts
					(xy 120.047258 -358.415336) (xy 120.864884 -358.415336) (xy 120.864884 -360.802936) (xy 120.047258 -360.802936)
				)
			)
		)
	)
)
